(kicad_pcb
	(version 20211014)
	(generator pcbnew)
	(general
    (thickness 1.6)
  )
	(paper "A4")
	(title_block
    (title "SA800U (Snapdragon 845) Baseboard")
    (date "2023-10-19")
    (rev "1.0.3")
    (company "Antmicro Ltd.")
    (comment 1 "www.antmicro.com")
		(comment 9 "footprints 174-183 of 589")
	)
	(layers
    (0 "F.Cu" signal)
    (1 "In1.Cu" power)
    (2 "In2.Cu" signal)
    (3 "In3.Cu" signal)
    (4 "In4.Cu" power)
    (31 "B.Cu" signal)
    (32 "B.Adhes" user "B.Adhesive")
    (33 "F.Adhes" user "F.Adhesive")
    (34 "B.Paste" user)
    (35 "F.Paste" user)
    (36 "B.SilkS" user "B.Silkscreen")
    (37 "F.SilkS" user "F.Silkscreen")
    (38 "B.Mask" user)
    (39 "F.Mask" user)
    (40 "Dwgs.User" user "User.Drawings")
    (41 "Cmts.User" user "User.Comments")
    (42 "Eco1.User" user "User.Eco1")
    (43 "Eco2.User" user "User.Eco2")
    (44 "Edge.Cuts" user)
    (45 "Margin" user)
    (46 "B.CrtYd" user "B.Courtyard")
    (47 "F.CrtYd" user "F.Courtyard")
    (48 "B.Fab" user)
    (49 "F.Fab" user)
  )
	(footprint "sa800u-baseboard-hw-footprints:LED_0603_1608Metric_G" (layer "F.Cu")
    (tedit 60C2DD7B)
    (at 153.2 134.34 180)
    (descr "LED SMD 0603 Green")
    (tags "LED SMD 0603 Green")
    (property "Author" "Antmicro")
    (property "License" "Apache-2.0")
    (property "MPN" "KP-1608ZGC")
    (property "Manufacturer" "Kingbright")
    (property "Sheetfile" "som.kicad_sch")
    (property "Sheetname" "SoM")
    (attr smd)
    (fp_text reference "D16" (at 1.08 -1.26 180) (layer "F.SilkS")
      (effects (font (size 0.7 0.7) (thickness 0.15)) (justify left bottom))
    )
    (fp_text value "KP-1608EC" (at 0 1.6 180) (layer "F.Fab")
      (effects (font (size 0.7 0.7) (thickness 0.15)) (justify left bottom))
    )
    (fp_text user "License: Apache-2.0" (at -1.31 5.769 180) (layer "F.Fab") hide
      (effects (font (size 0.7 0.7) (thickness 0.15)) (justify left bottom))
    )
    (fp_text user "Author: Antmicro" (at -1.31 4.769 180) (layer "F.Fab") hide
      (effects (font (size 0.7 0.7) (thickness 0.15)) (justify left bottom))
    )
    (fp_text user "${REFERENCE}" (at -1.31 3.769 180) (layer "F.Fab") hide
      (effects (font (size 0.7 0.7) (thickness 0.15)) (justify left bottom))
    )
    (fp_line (start -0.106328 -0.200008) (end -0.106328 0.199992) (layer "F.SilkS") (width 0.1))
    (fp_line (start 1.25 0.32) (end 1.25 -0.32) (layer "F.SilkS") (width 0.15))
    (fp_line (start -0.106328 -0.000008) (end -0.29 0) (layer "F.SilkS") (width 0.1))
    (fp_line (start 0.093672 -0.000008) (end 0.293672 -0.000008) (layer "F.SilkS") (width 0.1))
    (fp_line (start 0.093672 -0.200008) (end 0.093672 0.199992) (layer "F.SilkS") (width 0.1))
    (fp_line (start 0.093672 -0.000008) (end -0.106328 0.199992) (layer "F.SilkS") (width 0.1))
    (fp_line (start -0.27 0.351) (end 0.27 0.351) (layer "F.SilkS") (width 0.15))
    (fp_line (start -0.27 -0.35) (end 0.27 -0.35) (layer "F.SilkS") (width 0.15))
    (fp_line (start -0.106328 -0.200008) (end 0.093672 -0.000008) (layer "F.SilkS") (width 0.1))
    (fp_rect (start 1.26 0.65) (end -1.26 -0.65) (layer "F.CrtYd") (width 0.05) (fill none))
    (fp_line (start -0.599 0) (end -0.201 0) (layer "F.Fab") (width 0.15))
    (fp_line (start -0.201 -0.2) (end -0.201 0) (layer "F.Fab") (width 0.15))
    (fp_line (start -0.201 0) (end -0.201 0.202) (layer "F.Fab") (width 0.15))
    (fp_line (start 0.199 0) (end 0.597 0) (layer "F.Fab") (width 0.15))
    (fp_line (start 0.199 0.202) (end 0.199 -0.1) (layer "F.Fab") (width 0.15))
    (fp_line (start 0.101 0) (end -0.201 -0.2) (layer "F.Fab") (width 0.15))
    (fp_line (start -0.201 0.202) (end 0.101 0) (layer "F.Fab") (width 0.15))
    (fp_line (start 0.199 -0.2) (end 0.199 -0.1) (layer "F.Fab") (width 0.15))
    (fp_rect (start -0.848 -0.4) (end 0.85 0.402) (layer "F.Fab") (width 0.15) (fill none))
    (pad "1" smd rect (at -0.75 0) (size 0.8 0.8) (layers "F.Cu" "F.Paste" "F.Mask")
      (net 133 "5V_SYS") (pinfunction "1") (pintype "passive"))
    (pad "2" smd rect (at 0.75 0) (size 0.8 0.8) (layers "F.Cu" "F.Paste" "F.Mask")
      (net 75 "Net-(D16-Pad2)") (pinfunction "2") (pintype "passive"))
  )
	(footprint "sa800u-baseboard-hw-footprints:R_0402_1005Metric" (layer "F.Cu")
    (tedit 5FD9C158)
    (at 150.8 141.8)
    (descr "Resistor SMD 0402")
    (tags "resistor SMD 0402")
    (property "Author" "Antmicro")
    (property "License" "Apache-2.0")
    (property "MPN" "CR0402-FX-1002GLF")
    (property "Manufacturer" "Bourns")
    (property "Sheetfile" "som.kicad_sch")
    (property "Sheetname" "SoM")
    (property "Tolerance" "1%")
    (property "Val" "10k")
    (attr smd)
    (fp_text reference "R78" (at -1.09 1.32) (layer "F.SilkS")
      (effects (font (size 0.7 0.7) (thickness 0.15)) (justify left bottom))
    )
    (fp_text value "R_10k_0402" (at 0 1.4) (layer "F.Fab")
      (effects (font (size 0.7 0.7) (thickness 0.15)) (justify left bottom))
    )
    (fp_text user "Author: Antmicro" (at -0.95 4.169) (layer "F.Fab") hide
      (effects (font (size 0.7 0.7) (thickness 0.15)) (justify left bottom))
    )
    (fp_text user "License: Apache-2.0" (at -0.95 5.169) (layer "F.Fab") hide
      (effects (font (size 0.7 0.7) (thickness 0.15)) (justify left bottom))
    )
    (fp_text user "${REFERENCE}" (at -0.95 3.168) (layer "F.Fab") hide
      (effects (font (size 0.7 0.7) (thickness 0.15)) (justify left bottom))
    )
    (fp_rect (start -0.93 -0.47) (end 0.93 0.47) (layer "F.CrtYd") (width 0.05) (fill none))
    (fp_rect (start -0.5 -0.25) (end 0.5 0.25) (layer "F.Fab") (width 0.15) (fill none))
    (pad "1" smd roundrect (at -0.485 0) (size 0.59 0.64) (layers "F.Cu" "F.Paste" "F.Mask") (roundrect_rratio 0.25)
      (net 386 "Net-(Q6-Pad3)") (pintype "passive"))
    (pad "2" smd roundrect (at 0.485 0) (size 0.59 0.64) (layers "F.Cu" "F.Paste" "F.Mask") (roundrect_rratio 0.25)
      (net 372 "Net-(D15-Pad2)") (pintype "passive"))
  )
	(footprint "sa800u-baseboard-hw-footprints:R_0402_1005Metric" (layer "F.Cu")
    (tedit 5FD9C158)
    (at 150.8 134.2)
    (descr "Resistor SMD 0402")
    (tags "resistor SMD 0402")
    (property "Author" "Antmicro")
    (property "License" "Apache-2.0")
    (property "MPN" "CR0402-FX-1002GLF")
    (property "Manufacturer" "Bourns")
    (property "Sheetfile" "som.kicad_sch")
    (property "Sheetname" "SoM")
    (property "Tolerance" "1%")
    (property "Val" "10k")
    (attr smd)
    (fp_text reference "R79" (at -1.09 1.33) (layer "F.SilkS")
      (effects (font (size 0.7 0.7) (thickness 0.15)) (justify left bottom))
    )
    (fp_text value "R_10k_0402" (at 0 1.4) (layer "F.Fab")
      (effects (font (size 0.7 0.7) (thickness 0.15)) (justify left bottom))
    )
    (fp_text user "License: Apache-2.0" (at -0.95 5.169) (layer "F.Fab") hide
      (effects (font (size 0.7 0.7) (thickness 0.15)) (justify left bottom))
    )
    (fp_text user "${REFERENCE}" (at -0.95 3.168) (layer "F.Fab") hide
      (effects (font (size 0.7 0.7) (thickness 0.15)) (justify left bottom))
    )
    (fp_text user "Author: Antmicro" (at -0.95 4.169) (layer "F.Fab") hide
      (effects (font (size 0.7 0.7) (thickness 0.15)) (justify left bottom))
    )
    (fp_rect (start -0.93 -0.47) (end 0.93 0.47) (layer "F.CrtYd") (width 0.05) (fill none))
    (fp_rect (start -0.5 -0.25) (end 0.5 0.25) (layer "F.Fab") (width 0.15) (fill none))
    (pad "1" smd roundrect (at -0.485 0) (size 0.59 0.64) (layers "F.Cu" "F.Paste" "F.Mask") (roundrect_rratio 0.25)
      (net 387 "Net-(Q7-Pad3)") (pintype "passive"))
    (pad "2" smd roundrect (at 0.485 0) (size 0.59 0.64) (layers "F.Cu" "F.Paste" "F.Mask") (roundrect_rratio 0.25)
      (net 75 "Net-(D16-Pad2)") (pintype "passive"))
  )
	(footprint "sa800u-baseboard-hw-footprints:R_0402_1005Metric" (layer "F.Cu")
    (tedit 5FD9C158)
    (at 87 132.4 -90)
    (descr "Resistor SMD 0402")
    (tags "resistor SMD 0402")
    (property "Author" "Antmicro")
    (property "License" "Apache-2.0")
    (property "MPN" "CR0402-FX-1101GLF")
    (property "Manufacturer" "Bourns")
    (property "Sheetfile" "usb-pd.kicad_sch")
    (property "Sheetname" "USB-PD")
    (property "Tolerance" "1%")
    (property "Val" "1k1")
    (attr smd)
    (fp_text reference "R169" (at -0.88 -0.22 -90) (layer "F.SilkS")
      (effects (font (size 0.7 0.7) (thickness 0.15)) (justify left bottom))
    )
    (fp_text value "R_1k1_0402" (at 0 1.4 -90) (layer "F.Fab")
      (effects (font (size 0.7 0.7) (thickness 0.15)) (justify left bottom))
    )
    (fp_text user "License: Apache-2.0" (at -0.95 5.169 -90) (layer "F.Fab") hide
      (effects (font (size 0.7 0.7) (thickness 0.15)) (justify left bottom))
    )
    (fp_text user "${REFERENCE}" (at -0.95 3.168 -90) (layer "F.Fab") hide
      (effects (font (size 0.7 0.7) (thickness 0.15)) (justify left bottom))
    )
    (fp_text user "Author: Antmicro" (at -0.95 4.169 -90) (layer "F.Fab") hide
      (effects (font (size 0.7 0.7) (thickness 0.15)) (justify left bottom))
    )
    (fp_rect (start -0.93 -0.47) (end 0.93 0.47) (layer "F.CrtYd") (width 0.05) (fill none))
    (fp_rect (start -0.5 -0.25) (end 0.5 0.25) (layer "F.Fab") (width 0.15) (fill none))
    (pad "1" smd roundrect (at -0.485 0 270) (size 0.59 0.64) (layers "F.Cu" "F.Paste" "F.Mask") (roundrect_rratio 0.25)
      (net 142 "PD_VDD") (pintype "passive"))
    (pad "2" smd roundrect (at 0.485 0 270) (size 0.59 0.64) (layers "F.Cu" "F.Paste" "F.Mask") (roundrect_rratio 0.25)
      (net 468 "/USB-PD/DISCH") (pintype "passive"))
  )
	(footprint "sa800u-baseboard-hw-footprints:R_0402_1005Metric" (layer "F.Cu")
    (tedit 5FD9C158)
    (at 92.85 126 180)
    (descr "Resistor SMD 0402")
    (tags "resistor SMD 0402")
    (property "Author" "Antmicro")
    (property "License" "Apache-2.0")
    (property "MPN" "CR0402-FX-4701GLF")
    (property "Manufacturer" "Bourns")
    (property "Sheetfile" "usb-pd.kicad_sch")
    (property "Sheetname" "USB-PD")
    (property "Tolerance" "1%")
    (property "Val" "4k7")
    (attr smd)
    (fp_text reference "R170" (at 3.75 -0.32 180) (layer "F.SilkS")
      (effects (font (size 0.7 0.7) (thickness 0.15)) (justify left bottom))
    )
    (fp_text value "R_4k7_0402" (at 0 1.4 180) (layer "F.Fab")
      (effects (font (size 0.7 0.7) (thickness 0.15)) (justify left bottom))
    )
    (fp_text user "License: Apache-2.0" (at -0.95 5.169 180) (layer "F.Fab") hide
      (effects (font (size 0.7 0.7) (thickness 0.15)) (justify left bottom))
    )
    (fp_text user "Author: Antmicro" (at -0.95 4.169 180) (layer "F.Fab") hide
      (effects (font (size 0.7 0.7) (thickness 0.15)) (justify left bottom))
    )
    (fp_text user "${REFERENCE}" (at -0.95 3.168 180) (layer "F.Fab") hide
      (effects (font (size 0.7 0.7) (thickness 0.15)) (justify left bottom))
    )
    (fp_rect (start -0.93 -0.47) (end 0.93 0.47) (layer "F.CrtYd") (width 0.05) (fill none))
    (fp_rect (start -0.5 -0.25) (end 0.5 0.25) (layer "F.Fab") (width 0.15) (fill none))
    (pad "1" smd roundrect (at -0.485 0 180) (size 0.59 0.64) (layers "F.Cu" "F.Paste" "F.Mask") (roundrect_rratio 0.25)
      (net 334 "/USB-PD/GPIO") (pintype "passive"))
    (pad "2" smd roundrect (at 0.485 0 180) (size 0.59 0.64) (layers "F.Cu" "F.Paste" "F.Mask") (roundrect_rratio 0.25)
      (net 132 "VREG_S4A_1V8") (pintype "passive"))
  )
	(footprint "sa800u-baseboard-hw-footprints:R_0402_1005Metric" (layer "F.Cu")
    (tedit 5FD9C158)
    (at 92.85 128 180)
    (descr "Resistor SMD 0402")
    (tags "resistor SMD 0402")
    (property "Author" "Antmicro")
    (property "License" "Apache-2.0")
    (property "MPN" "CR0402-FX-4701GLF")
    (property "Manufacturer" "Bourns")
    (property "Sheetfile" "usb-pd.kicad_sch")
    (property "Sheetname" "USB-PD")
    (property "Tolerance" "1%")
    (property "Val" "4k7")
    (attr smd)
    (fp_text reference "R172" (at 3.75 -0.32 180) (layer "F.SilkS")
      (effects (font (size 0.7 0.7) (thickness 0.15)) (justify left bottom))
    )
    (fp_text value "R_4k7_0402" (at 0 1.4 180) (layer "F.Fab")
      (effects (font (size 0.7 0.7) (thickness 0.15)) (justify left bottom))
    )
    (fp_text user "License: Apache-2.0" (at -0.95 5.169 180) (layer "F.Fab") hide
      (effects (font (size 0.7 0.7) (thickness 0.15)) (justify left bottom))
    )
    (fp_text user "${REFERENCE}" (at -0.95 3.168 180) (layer "F.Fab") hide
      (effects (font (size 0.7 0.7) (thickness 0.15)) (justify left bottom))
    )
    (fp_text user "Author: Antmicro" (at -0.95 4.169 180) (layer "F.Fab") hide
      (effects (font (size 0.7 0.7) (thickness 0.15)) (justify left bottom))
    )
    (fp_rect (start -0.93 -0.47) (end 0.93 0.47) (layer "F.CrtYd") (width 0.05) (fill none))
    (fp_rect (start -0.5 -0.25) (end 0.5 0.25) (layer "F.Fab") (width 0.15) (fill none))
    (pad "1" smd roundrect (at -0.485 0 180) (size 0.59 0.64) (layers "F.Cu" "F.Paste" "F.Mask") (roundrect_rratio 0.25)
      (net 335 "/USB-PD/ATTACH") (pintype "passive"))
    (pad "2" smd roundrect (at 0.485 0 180) (size 0.59 0.64) (layers "F.Cu" "F.Paste" "F.Mask") (roundrect_rratio 0.25)
      (net 132 "VREG_S4A_1V8") (pintype "passive"))
  )
	(footprint "sa800u-baseboard-hw-footprints:R_0402_1005Metric" (layer "F.Cu")
    (tedit 5FD9C158)
    (at 92.85 127 180)
    (descr "Resistor SMD 0402")
    (tags "resistor SMD 0402")
    (property "Author" "Antmicro")
    (property "License" "Apache-2.0")
    (property "MPN" "CR0402-FX-4701GLF")
    (property "Manufacturer" "Bourns")
    (property "Sheetfile" "usb-pd.kicad_sch")
    (property "Sheetname" "USB-PD")
    (property "Tolerance" "1%")
    (property "Val" "4k7")
    (attr smd)
    (fp_text reference "R168" (at 3.75 -0.32 180) (layer "F.SilkS")
      (effects (font (size 0.7 0.7) (thickness 0.15)) (justify left bottom))
    )
    (fp_text value "R_4k7_0402" (at 0 1.4 180) (layer "F.Fab")
      (effects (font (size 0.7 0.7) (thickness 0.15)) (justify left bottom))
    )
    (fp_text user "License: Apache-2.0" (at -0.95 5.169 180) (layer "F.Fab") hide
      (effects (font (size 0.7 0.7) (thickness 0.15)) (justify left bottom))
    )
    (fp_text user "${REFERENCE}" (at -0.95 3.168 180) (layer "F.Fab") hide
      (effects (font (size 0.7 0.7) (thickness 0.15)) (justify left bottom))
    )
    (fp_text user "Author: Antmicro" (at -0.95 4.169 180) (layer "F.Fab") hide
      (effects (font (size 0.7 0.7) (thickness 0.15)) (justify left bottom))
    )
    (fp_rect (start -0.93 -0.47) (end 0.93 0.47) (layer "F.CrtYd") (width 0.05) (fill none))
    (fp_rect (start -0.5 -0.25) (end 0.5 0.25) (layer "F.Fab") (width 0.15) (fill none))
    (pad "1" smd roundrect (at -0.485 0 180) (size 0.59 0.64) (layers "F.Cu" "F.Paste" "F.Mask") (roundrect_rratio 0.25)
      (net 333 "/USB-PD/AB_SIDE") (pintype "passive"))
    (pad "2" smd roundrect (at 0.485 0 180) (size 0.59 0.64) (layers "F.Cu" "F.Paste" "F.Mask") (roundrect_rratio 0.25)
      (net 132 "VREG_S4A_1V8") (pintype "passive"))
  )
	(footprint "sa800u-baseboard-hw-footprints:R_0402_1005Metric" (layer "F.Cu")
    (tedit 5FD9C158)
    (at 92.85 129 180)
    (descr "Resistor SMD 0402")
    (tags "resistor SMD 0402")
    (property "Author" "Antmicro")
    (property "License" "Apache-2.0")
    (property "MPN" "CR0402-FX-4701GLF")
    (property "Manufacturer" "Bourns")
    (property "Sheetfile" "usb-pd.kicad_sch")
    (property "Sheetname" "USB-PD")
    (property "Tolerance" "1%")
    (property "Val" "4k7")
    (attr smd)
    (fp_text reference "R167" (at 3.75 -0.32 180) (layer "F.SilkS")
      (effects (font (size 0.7 0.7) (thickness 0.15)) (justify left bottom))
    )
    (fp_text value "R_4k7_0402" (at 0 1.4 180) (layer "F.Fab")
      (effects (font (size 0.7 0.7) (thickness 0.15)) (justify left bottom))
    )
    (fp_text user "Author: Antmicro" (at -0.95 4.169 180) (layer "F.Fab") hide
      (effects (font (size 0.7 0.7) (thickness 0.15)) (justify left bottom))
    )
    (fp_text user "License: Apache-2.0" (at -0.95 5.169 180) (layer "F.Fab") hide
      (effects (font (size 0.7 0.7) (thickness 0.15)) (justify left bottom))
    )
    (fp_text user "${REFERENCE}" (at -0.95 3.168 180) (layer "F.Fab") hide
      (effects (font (size 0.7 0.7) (thickness 0.15)) (justify left bottom))
    )
    (fp_rect (start -0.93 -0.47) (end 0.93 0.47) (layer "F.CrtYd") (width 0.05) (fill none))
    (fp_rect (start -0.5 -0.25) (end 0.5 0.25) (layer "F.Fab") (width 0.15) (fill none))
    (pad "1" smd roundrect (at -0.485 0 180) (size 0.59 0.64) (layers "F.Cu" "F.Paste" "F.Mask") (roundrect_rratio 0.25)
      (net 332 "/USB-PD/ALERT") (pintype "passive"))
    (pad "2" smd roundrect (at 0.485 0 180) (size 0.59 0.64) (layers "F.Cu" "F.Paste" "F.Mask") (roundrect_rratio 0.25)
      (net 132 "VREG_S4A_1V8") (pintype "passive"))
  )
	(footprint "sa800u-baseboard-hw-footprints:R_0402_1005Metric" (layer "F.Cu")
    (tedit 5FD9C158)
    (at 145.9 128.8 -90)
    (descr "Resistor SMD 0402")
    (tags "resistor SMD 0402")
    (property "Author" "Antmicro")
    (property "DNP" "DNP")
    (property "License" "Apache-2.0")
    (property "MPN" "CR0402-FX-1004GLF")
    (property "Manufacturer" "Bourns")
    (property "Sheetfile" "hdmi-converter.kicad_sch")
    (property "Sheetname" "HDMI converter")
    (property "Tolerance" "1%")
    (property "Val" "1M")
    (attr exclude_from_pos_files)
    (fp_text reference "R21" (at -0.84 -0.43 -90) (layer "F.SilkS")
      (effects (font (size 0.7 0.7) (thickness 0.15)) (justify left bottom))
    )
    (fp_text value "R_1M_0402" (at 0 1.4 -90) (layer "F.Fab")
      (effects (font (size 0.7 0.7) (thickness 0.15)) (justify left bottom))
    )
    (fp_text user "Author: Antmicro" (at -0.95 4.169 -90) (layer "F.Fab") hide
      (effects (font (size 0.7 0.7) (thickness 0.15)) (justify left bottom))
    )
    (fp_text user "License: Apache-2.0" (at -0.95 5.169 -90) (layer "F.Fab") hide
      (effects (font (size 0.7 0.7) (thickness 0.15)) (justify left bottom))
    )
    (fp_text user "${REFERENCE}" (at -0.95 3.168 -90) (layer "F.Fab") hide
      (effects (font (size 0.7 0.7) (thickness 0.15)) (justify left bottom))
    )
    (fp_rect (start -0.93 -0.47) (end 0.93 0.47) (layer "F.CrtYd") (width 0.05) (fill none))
    (fp_rect (start -0.5 -0.25) (end 0.5 0.25) (layer "F.Fab") (width 0.15) (fill none))
    (pad "1" smd roundrect (at -0.485 0 270) (size 0.59 0.64) (layers "F.Cu" "F.Paste" "F.Mask") (roundrect_rratio 0.25)
      (net 190 "/HDMI converter/XTALO") (pintype "passive"))
    (pad "2" smd roundrect (at 0.485 0 270) (size 0.59 0.64) (layers "F.Cu" "F.Paste" "F.Mask") (roundrect_rratio 0.25)
      (net 192 "/HDMI converter/XTALI") (pintype "passive"))
  )
	(footprint "sa800u-baseboard-hw-footprints:R_0402_1005Metric" (layer "F.Cu")
    (tedit 5FD9C158)
    (at 145.75 136.9 -90)
    (descr "Resistor SMD 0402")
    (tags "resistor SMD 0402")
    (property "Author" "Antmicro")
    (property "License" "Apache-2.0")
    (property "MPN" "CR0402-FX-5100GLF")
    (property "Manufacturer" "Bourns")
    (property "Sheetfile" "hdmi-converter.kicad_sch")
    (property "Sheetname" "HDMI converter")
    (property "Tolerance" "1%")
    (property "Val" "510R")
    (attr smd)
    (fp_text reference "R55" (at -4.601 16.48 -90) (layer "F.SilkS")
      (effects (font (size 0.7 0.7) (thickness 0.15)) (justify left bottom))
    )
    (fp_text value "R_510R_0402" (at 0 1.4 -90) (layer "F.Fab")
      (effects (font (size 0.7 0.7) (thickness 0.15)) (justify left bottom))
    )
    (fp_text user "Author: Antmicro" (at -0.95 4.169 -90) (layer "F.Fab") hide
      (effects (font (size 0.7 0.7) (thickness 0.15)) (justify left bottom))
    )
    (fp_text user "License: Apache-2.0" (at -0.95 5.169 -90) (layer "F.Fab") hide
      (effects (font (size 0.7 0.7) (thickness 0.15)) (justify left bottom))
    )
    (fp_text user "${REFERENCE}" (at -0.95 3.168 -90) (layer "F.Fab") hide
      (effects (font (size 0.7 0.7) (thickness 0.15)) (justify left bottom))
    )
    (fp_rect (start -0.93 -0.47) (end 0.93 0.47) (layer "F.CrtYd") (width 0.05) (fill none))
    (fp_rect (start -0.5 -0.25) (end 0.5 0.25) (layer "F.Fab") (width 0.15) (fill none))
    (pad "1" smd roundrect (at -0.485 0 270) (size 0.59 0.64) (layers "F.Cu" "F.Paste" "F.Mask") (roundrect_rratio 0.25)
      (net 195 "/HDMI converter/HDMI_TX2_N") (pintype "passive"))
    (pad "2" smd roundrect (at 0.485 0 270) (size 0.59 0.64) (layers "F.Cu" "F.Paste" "F.Mask") (roundrect_rratio 0.25)
      (net 209 "/HDMI converter/VCOM") (pintype "passive"))
  )
)
